# BASEBOARD_FAB2 (Tioga Pass) — schematic netlist excerpt (pin names and nets, part order shuffled) for the footprints in the layout excerpt that follows; sources: Cadence DE-HDL packaged netlist, KiCad conversion of Wiwynn_Tioga_Pass_MB.brd

EU3P1  PXE1110B  IC  pkg QFN  page 211
  DNC(0)  = NC
  DNC(1)  = NC
  BPWM1  = NC
  DNC(2)  = NC
  APWM1  = VR_PVCCIO_CPU0_PWM1
  SDA  = SMB_VR_STBY_LVC3_SDA
  SCL  = SMB_VR_STBY_LVC3_SCL
  RESET_N  = NC
  AVRRDY  = PWRGD_PVCCIO_CPU0_R
  AVREN  = VR_PVCCIO_CPU0_EN
  VRHOT_N  = IRQ_PVCCIO_CPU0_VRHOT_N
  PINALRT_N  = NC
  MP0  = NC
  MP1  = NC
  VCLK  = SVID_CLK_PVCCIO_CPU0
  VDIO  = SVID_VDIO_PVCCIO_CPU0
  VALRT_N  = SVID_ALERT_PVCCIO_CPU0
  MP2  = NC
  AVSEN  = VR_PVCCIO_CPU0_AVSP
  AVREF  = VSENSE_PVCCIO_CPU0_AVSN
  AIREF1  = VR_PVCCIO_CPU0_AIREF1
  AISEN1  = ISENSE_PVCCIO_CPU0_PH1_IMON
  GND(1)  = GND
  DNC(3)  = NC
  BIREF1  = NC
  BISEN1  = GND
  GND(0)  = GND
  DNC(4)  = NC
  BVSEN  = NC
  BVREF  = NC
  MP3  = NC
  MP4  = PU_VR_PVCCIO_CPU0_FAULT1
  XADDR2  = VR_PVCCIO_CPU0_XADDR2
  BTSEN  = NC
  ATSEN  = A_TSENSE_PVCCIO_CPU0
  XADDR1  = VR_PVCCIO_CPU0_XADDR1
  VINSEN  = VR_PVCCIO_CPU0_VINSEN
  IINSEN  = NC
  VDD  = VR_PVCCIO_CPU0_VDD
  VD12  = VR_PVCCIO_CPU0_VD12
  THPAD  = GND

(kicad_pcb
	(version 20260206)
	(generator "pcbnew")
	(generator_version "10.0")
	(general
		(thickness 1.6)
		(legacy_teardrops no)
	)
	(paper "A4")
	(title_block
		(title "Wiwynn_Tioga_Pass_MB.brd")
		(comment 1 "Tioga Pass / footprint 3922 of 4770 (EU3P1), pads 1-17 of 41")
	)
	(layers
		(0 "F.Cu" signal "TOP")
		(4 "In1.Cu" signal "L2GND")
		(6 "In2.Cu" signal "L3")
		(8 "In3.Cu" signal "L4GND")
		(10 "In4.Cu" signal "L5")
		(12 "In5.Cu" signal "L6GND")
		(14 "In6.Cu" signal "L7VCC")
		(16 "In7.Cu" signal "L8VCC")
		(18 "In8.Cu" signal "L9GND")
		(20 "In9.Cu" signal "L10")
		(22 "In10.Cu" signal "L11GND")
		(24 "In11.Cu" signal "L12")
		(26 "In12.Cu" signal "L13GND")
		(2 "B.Cu" signal "BOTTOM")
		(9 "F.Adhes" user "F.Adhesive")
		(11 "B.Adhes" user "B.Adhesive")
		(13 "F.Paste" user "Package Geometry/Pastemask Top")
		(15 "B.Paste" user "Package Geometry/Pastemask Bottom")
		(5 "F.SilkS" user "Ref Des/Silkscreen Top")
		(7 "B.SilkS" user "Ref Des/Silkscreen Bottom")
		(1 "F.Mask" user "Board Geometry/Soldermask Top")
		(3 "B.Mask" user "Board Geometry/Soldermask Bottom")
		(17 "Dwgs.User" user "User.Drawings")
		(19 "Cmts.User" user "User.Comments")
		(21 "Eco1.User" user "User.Eco1")
		(23 "Eco2.User" user "User.Eco2")
		(25 "Edge.Cuts" user "Board Geometry/Outline")
		(27 "Margin" user)
		(31 "F.CrtYd" user "Package Geometry/Place Bound Top")
		(29 "B.CrtYd" user "Package Geometry/Place Bound Bottom")
		(35 "F.Fab" user "Ref Des/Assembly Top")
		(33 "B.Fab" user "Ref Des/Assembly Bottom")
	)
	(footprint ""
		(layer "B.Cu")
		(at 346.5322 -87.4522 -90)
		(property "Reference" "EU3P1"
			(at -1.80975 3.2893 0)
			(unlocked yes)
			(layer "B.SilkS")
			(effects
				(font
					(size 0.7874 0.5842)
					(thickness 0.1524)
				)
				(justify left mirror)
			)
		)
		(property "Value" ""
			(at 0 0 90)
			(layer "B.Fab")
			(effects
				(font
					(size 1.27 1.27)
				)
				(justify mirror)
			)
		)
		(duplicate_pad_numbers_are_jumpers no)
		(pad "1" smd custom
			(at 2.4511 -1.800098 90)
			(size 0.0508 0.0508)
			(layers "B.Cu" "B.Mask" "B.Paste")
			(net "Net_331")
			(options
				(clearance outline)
				(anchor circle)
			)
			(primitives
				(gr_poly
					(pts
						(arc
							(start 0.254 0.1016)
							(mid 0.3556 0)
							(end 0.254 -0.1016)
						)
						(xy -0.3556 -0.1016) (xy -0.3556 0.1016)
					)
					(width 0)
					(fill yes)
				)
			)
		)
		(pad "2" smd custom
			(at 2.4511 -1.400048 90)
			(size 0.0508 0.0508)
			(layers "B.Cu" "B.Mask" "B.Paste")
			(net "Net_332")
			(options
				(clearance outline)
				(anchor circle)
			)
			(primitives
				(gr_poly
					(pts
						(arc
							(start 0.254 0.1016)
							(mid 0.3556 0)
							(end 0.254 -0.1016)
						)
						(xy -0.3556 -0.1016) (xy -0.3556 0.1016)
					)
					(width 0)
					(fill yes)
				)
			)
		)
		(pad "3" smd custom
			(at 2.4511 -0.999998 90)
			(size 0.0508 0.0508)
			(layers "B.Cu" "B.Mask" "B.Paste")
			(net "Net_269")
			(options
				(clearance outline)
				(anchor circle)
			)
			(primitives
				(gr_poly
					(pts
						(arc
							(start 0.254 0.1016)
							(mid 0.3556 0)
							(end 0.254 -0.1016)
						)
						(xy -0.3556 -0.1016) (xy -0.3556 0.1016)
					)
					(width 0)
					(fill yes)
				)
			)
		)
		(pad "4" smd custom
			(at 2.4511 -0.599948 90)
			(size 0.0508 0.0508)
			(layers "B.Cu" "B.Mask" "B.Paste")
			(net "Net_333")
			(options
				(clearance outline)
				(anchor circle)
			)
			(primitives
				(gr_poly
					(pts
						(arc
							(start 0.254 0.1016)
							(mid 0.3556 0)
							(end 0.254 -0.1016)
						)
						(xy -0.3556 -0.1016) (xy -0.3556 0.1016)
					)
					(width 0)
					(fill yes)
				)
			)
		)
		(pad "5" smd custom
			(at 2.4511 -0.199898 90)
			(size 0.0508 0.0508)
			(layers "B.Cu" "B.Mask" "B.Paste")
			(net "VR_PVCCIO_CPU0_PWM1")
			(options
				(clearance outline)
				(anchor circle)
			)
			(primitives
				(gr_poly
					(pts
						(arc
							(start 0.254 0.1016)
							(mid 0.3556 0)
							(end 0.254 -0.1016)
						)
						(xy -0.3556 -0.1016) (xy -0.3556 0.1016)
					)
					(width 0)
					(fill yes)
				)
			)
		)
		(pad "6" smd custom
			(at 2.4511 0.199898 90)
			(size 0.0508 0.0508)
			(layers "B.Cu" "B.Mask" "B.Paste")
			(net "SMB_VR_STBY_LVC3_SDA")
			(options
				(clearance outline)
				(anchor circle)
			)
			(primitives
				(gr_poly
					(pts
						(arc
							(start 0.254 0.1016)
							(mid 0.3556 0)
							(end 0.254 -0.1016)
						)
						(xy -0.3556 -0.1016) (xy -0.3556 0.1016)
					)
					(width 0)
					(fill yes)
				)
			)
		)
		(pad "7" smd custom
			(at 2.4511 0.599948 90)
			(size 0.0508 0.0508)
			(layers "B.Cu" "B.Mask" "B.Paste")
			(net "SMB_VR_STBY_LVC3_SCL")
			(options
				(clearance outline)
				(anchor circle)
			)
			(primitives
				(gr_poly
					(pts
						(arc
							(start 0.254 0.1016)
							(mid 0.3556 0)
							(end 0.254 -0.1016)
						)
						(xy -0.3556 -0.1016) (xy -0.3556 0.1016)
					)
					(width 0)
					(fill yes)
				)
			)
		)
		(pad "8" smd custom
			(at 2.4511 0.999998 90)
			(size 0.0508 0.0508)
			(layers "B.Cu" "B.Mask" "B.Paste")
			(net "Net_270")
			(options
				(clearance outline)
				(anchor circle)
			)
			(primitives
				(gr_poly
					(pts
						(arc
							(start 0.254 0.1016)
							(mid 0.3556 0)
							(end 0.254 -0.1016)
						)
						(xy -0.3556 -0.1016) (xy -0.3556 0.1016)
					)
					(width 0)
					(fill yes)
				)
			)
		)
		(pad "9" smd custom
			(at 2.4511 1.400048 90)
			(size 0.0508 0.0508)
			(layers "B.Cu" "B.Mask" "B.Paste")
			(net "PWRGD_PVCCIO_CPU0_R")
			(options
				(clearance outline)
				(anchor circle)
			)
			(primitives
				(gr_poly
					(pts
						(arc
							(start 0.254 0.1016)
							(mid 0.3556 0)
							(end 0.254 -0.1016)
						)
						(xy -0.3556 -0.1016) (xy -0.3556 0.1016)
					)
					(width 0)
					(fill yes)
				)
			)
		)
		(pad "10" smd custom
			(at 2.4511 1.800098 90)
			(size 0.0508 0.0508)
			(layers "B.Cu" "B.Mask" "B.Paste")
			(net "VR_PVCCIO_CPU0_EN")
			(options
				(clearance outline)
				(anchor circle)
			)
			(primitives
				(gr_poly
					(pts
						(arc
							(start 0.254 0.1016)
							(mid 0.3556 0)
							(end 0.254 -0.1016)
						)
						(xy -0.3556 -0.1016) (xy -0.3556 0.1016)
					)
					(width 0)
					(fill yes)
				)
			)
		)
		(pad "11" smd custom
			(at 1.800098 2.4511 90)
			(size 0.0508 0.0508)
			(layers "B.Cu" "B.Mask" "B.Paste")
			(net "IRQ_PVCCIO_CPU0_VRHOT_N")
			(options
				(clearance outline)
				(anchor circle)
			)
			(primitives
				(gr_poly
					(pts
						(arc
							(start -0.1016 0.254)
							(mid 0 0.3556)
							(end 0.1016 0.254)
						)
						(xy 0.1016 -0.3556) (xy -0.1016 -0.3556)
					)
					(width 0)
					(fill yes)
				)
			)
		)
		(pad "12" smd custom
			(at 1.400048 2.4511 90)
			(size 0.0508 0.0508)
			(layers "B.Cu" "B.Mask" "B.Paste")
			(net "Net_257")
			(options
				(clearance outline)
				(anchor circle)
			)
			(primitives
				(gr_poly
					(pts
						(arc
							(start -0.1016 0.254)
							(mid 0 0.3556)
							(end 0.1016 0.254)
						)
						(xy 0.1016 -0.3556) (xy -0.1016 -0.3556)
					)
					(width 0)
					(fill yes)
				)
			)
		)
		(pad "13" smd custom
			(at 0.999998 2.4511 90)
			(size 0.0508 0.0508)
			(layers "B.Cu" "B.Mask" "B.Paste")
			(net "Net_255")
			(options
				(clearance outline)
				(anchor circle)
			)
			(primitives
				(gr_poly
					(pts
						(arc
							(start -0.1016 0.254)
							(mid 0 0.3556)
							(end 0.1016 0.254)
						)
						(xy 0.1016 -0.3556) (xy -0.1016 -0.3556)
					)
					(width 0)
					(fill yes)
				)
			)
		)
		(pad "14" smd custom
			(at 0.599948 2.4511 90)
			(size 0.0508 0.0508)
			(layers "B.Cu" "B.Mask" "B.Paste")
			(net "Net_256")
			(options
				(clearance outline)
				(anchor circle)
			)
			(primitives
				(gr_poly
					(pts
						(arc
							(start -0.1016 0.254)
							(mid 0 0.3556)
							(end 0.1016 0.254)
						)
						(xy 0.1016 -0.3556) (xy -0.1016 -0.3556)
					)
					(width 0)
					(fill yes)
				)
			)
		)
		(pad "15" smd custom
			(at 0.199898 2.4511 90)
			(size 0.0508 0.0508)
			(layers "B.Cu" "B.Mask" "B.Paste")
			(net "SVID_CLK_PVCCIO_CPU0")
			(options
				(clearance outline)
				(anchor circle)
			)
			(primitives
				(gr_poly
					(pts
						(arc
							(start -0.1016 0.254)
							(mid 0 0.3556)
							(end 0.1016 0.254)
						)
						(xy 0.1016 -0.3556) (xy -0.1016 -0.3556)
					)
					(width 0)
					(fill yes)
				)
			)
		)
		(pad "16" smd custom
			(at -0.199898 2.4511 90)
			(size 0.0508 0.0508)
			(layers "B.Cu" "B.Mask" "B.Paste")
			(net "SVID_VDIO_PVCCIO_CPU0")
			(options
				(clearance outline)
				(anchor circle)
			)
			(primitives
				(gr_poly
					(pts
						(arc
							(start -0.1016 0.254)
							(mid 0 0.3556)
							(end 0.1016 0.254)
						)
						(xy 0.1016 -0.3556) (xy -0.1016 -0.3556)
					)
					(width 0)
					(fill yes)
				)
			)
		)
		(pad "17" smd custom
			(at -0.599948 2.4511 90)
			(size 0.0508 0.0508)
			(layers "B.Cu" "B.Mask" "B.Paste")
			(net "SVID_ALERT_PVCCIO_CPU0")
			(options
				(clearance outline)
				(anchor circle)
			)
			(primitives
				(gr_poly
					(pts
						(arc
							(start -0.1016 0.254)
							(mid 0 0.3556)
							(end 0.1016 0.254)
						)
						(xy 0.1016 -0.3556) (xy -0.1016 -0.3556)
					)
					(width 0)
					(fill yes)
				)
			)
		)
	)
)
